(kicad_pcb
	(version 20260206)
	(generator "pcbnew")
	(generator_version "10.0")
	(general
		(thickness 1.6)
		(legacy_teardrops no)
	)
	(paper "A4")
	(title_block
		(title "baseboard — 13948-1b.1110WZS1818.brd")
		(comment 1 "Honey Badger (Wiwynn) / footprint 1534 of 2523 (CN8), pads 151-166 of 166")
	)
	(layers
		(0 "F.Cu" signal "TOP")
		(4 "In1.Cu" signal "L2GND")
		(6 "In2.Cu" signal "L3")
		(8 "In3.Cu" signal "L4VCC")
		(10 "In4.Cu" signal "L5VCC")
		(12 "In5.Cu" signal "L6")
		(14 "In6.Cu" signal "L7GND")
		(2 "B.Cu" signal "BOTTOM")
		(9 "F.Adhes" user "F.Adhesive")
		(11 "B.Adhes" user "B.Adhesive")
		(13 "F.Paste" user "Package Geometry/Pastemask Top")
		(15 "B.Paste" user "Package Geometry/Pastemask Bottom")
		(5 "F.SilkS" user "Ref Des/Silkscreen Top")
		(7 "B.SilkS" user "Ref Des/Silkscreen Bottom")
		(1 "F.Mask" user "Board Geometry/Soldermask Top")
		(3 "B.Mask" user "Board Geometry/Soldermask Bottom")
		(17 "Dwgs.User" user "User.Drawings")
		(19 "Cmts.User" user "User.Comments")
		(21 "Eco1.User" user "User.Eco1")
		(23 "Eco2.User" user "User.Eco2")
		(25 "Edge.Cuts" user "Board Geometry/Outline")
		(27 "Margin" user)
		(31 "F.CrtYd" user "Package Geometry/Place Bound Top")
		(29 "B.CrtYd" user "Package Geometry/Place Bound Bottom")
		(35 "F.Fab" user "Ref Des/Assembly Top")
		(33 "B.Fab" user "Ref Des/Assembly Bottom")
	)
	(footprint ""
		(layer "F.Cu")
		(at 209.799936 -77.0001 180)
		(property "Reference" "CN8"
			(at 0 0 180)
			(layer "F.SilkS")
			(hide yes)
			(effects
				(font
					(size 1.27 1.27)
				)
			)
		)
		(property "Value" "PCISLT164-44-GP"
			(at -23.3172 -6.8961 180)
			(unlocked yes)
			(layer "F.Fab")
			(hide yes)
			(effects
				(font
					(size 1.016 1.016)
					(thickness 0.1524)
				)
			)
		)
		(property "Device Type" "AAA-PCI-066-K06"
			(at -23.3172 -8.4201 180)
			(unlocked yes)
			(layer "F.Fab")
			(hide yes)
			(effects
				(font
					(size 1.016 1.016)
					(thickness 0.1524)
				)
			)
		)
		(duplicate_pad_numbers_are_jumpers no)
		(pad "B67" thru_hole circle
			(at 56.3499 1.24968 180)
			(size 1.0922 1.0922)
			(drill 0.7366)
			(layers "*.Cu" "*.Mask")
			(remove_unused_layers no)
			(net "PCIE_10G_CPU_TX0_P")
			(clearance 0.1778)
			(thermal_gap 0.1778)
		)
		(pad "B68" thru_hole circle
			(at 57.34939 3.24993 180)
			(size 1.0922 1.0922)
			(drill 0.7366)
			(layers "*.Cu" "*.Mask")
			(remove_unused_layers no)
			(net "PCIE_10G_CPU_TX0_N")
			(clearance 0.1778)
			(thermal_gap 0.1778)
		)
		(pad "B69" thru_hole circle
			(at 58.35015 1.24968 180)
			(size 1.0922 1.0922)
			(drill 0.7366)
			(layers "*.Cu" "*.Mask")
			(remove_unused_layers no)
			(net "GND")
			(clearance 0.1778)
			(thermal_gap 0.1778)
		)
		(pad "B70" thru_hole circle
			(at 59.34964 3.24993 180)
			(size 1.0922 1.0922)
			(drill 0.7366)
			(layers "*.Cu" "*.Mask")
			(remove_unused_layers no)
			(net "GND")
			(clearance 0.1778)
			(thermal_gap 0.1778)
		)
		(pad "B71" thru_hole circle
			(at 60.3504 1.24968 180)
			(size 1.0922 1.0922)
			(drill 0.7366)
			(layers "*.Cu" "*.Mask")
			(remove_unused_layers no)
			(net "PCIE_10G_CPU_TX1_P")
			(clearance 0.1778)
			(thermal_gap 0.1778)
		)
		(pad "B72" thru_hole circle
			(at 61.34989 3.24993 180)
			(size 1.0922 1.0922)
			(drill 0.7366)
			(layers "*.Cu" "*.Mask")
			(remove_unused_layers no)
			(net "PCIE_10G_CPU_TX1_N")
			(clearance 0.1778)
			(thermal_gap 0.1778)
		)
		(pad "B73" thru_hole circle
			(at 62.34938 1.24968 180)
			(size 1.0922 1.0922)
			(drill 0.7366)
			(layers "*.Cu" "*.Mask")
			(remove_unused_layers no)
			(net "GND")
			(clearance 0.1778)
			(thermal_gap 0.1778)
		)
		(pad "B74" thru_hole circle
			(at 63.35014 3.24993 180)
			(size 1.0922 1.0922)
			(drill 0.7366)
			(layers "*.Cu" "*.Mask")
			(remove_unused_layers no)
			(net "GND")
			(clearance 0.1778)
			(thermal_gap 0.1778)
		)
		(pad "B75" thru_hole circle
			(at 64.34963 1.24968 180)
			(size 1.0922 1.0922)
			(drill 0.7366)
			(layers "*.Cu" "*.Mask")
			(remove_unused_layers no)
			(net "PCIE_10G_CPU_TX2_P")
			(clearance 0.1778)
			(thermal_gap 0.1778)
		)
		(pad "B76" thru_hole circle
			(at 65.35039 3.24993 180)
			(size 1.0922 1.0922)
			(drill 0.7366)
			(layers "*.Cu" "*.Mask")
			(remove_unused_layers no)
			(net "PCIE_10G_CPU_TX2_N")
			(clearance 0.1778)
			(thermal_gap 0.1778)
		)
		(pad "B77" thru_hole circle
			(at 66.34988 1.24968 180)
			(size 1.0922 1.0922)
			(drill 0.7366)
			(layers "*.Cu" "*.Mask")
			(remove_unused_layers no)
			(net "GND")
			(clearance 0.1778)
			(thermal_gap 0.1778)
		)
		(pad "B78" thru_hole circle
			(at 67.34937 3.24993 180)
			(size 1.0922 1.0922)
			(drill 0.7366)
			(layers "*.Cu" "*.Mask")
			(remove_unused_layers no)
			(net "GND")
			(clearance 0.1778)
			(thermal_gap 0.1778)
		)
		(pad "B79" thru_hole circle
			(at 68.35013 1.24968 180)
			(size 1.0922 1.0922)
			(drill 0.7366)
			(layers "*.Cu" "*.Mask")
			(remove_unused_layers no)
			(net "PCIE_10G_CPU_TX3_P")
			(clearance 0.1778)
			(thermal_gap 0.1778)
		)
		(pad "B80" thru_hole circle
			(at 69.34962 3.24993 180)
			(size 1.0922 1.0922)
			(drill 0.7366)
			(layers "*.Cu" "*.Mask")
			(remove_unused_layers no)
			(net "PCIE_10G_CPU_TX3_N")
			(clearance 0.1778)
			(thermal_gap 0.1778)
		)
		(pad "B81" thru_hole circle
			(at 70.35038 1.24968 180)
			(size 1.0922 1.0922)
			(drill 0.7366)
			(layers "*.Cu" "*.Mask")
			(remove_unused_layers no)
			(net "PRSNT_MSB_B81")
			(clearance 0.1778)
			(thermal_gap 0.1778)
		)
		(pad "B82" thru_hole circle
			(at 71.34987 3.24993 180)
			(size 1.0922 1.0922)
			(drill 0.7366)
			(layers "*.Cu" "*.Mask")
			(remove_unused_layers no)
			(net "GND")
			(clearance 0.1778)
			(thermal_gap 0.1778)
		)
	)
)
